(kicad_pcb
	(version 20260206)
	(generator "pcbnew")
	(generator_version "10.0")
	(general
		(thickness 1.6)
		(legacy_teardrops no)
	)
	(paper "A4")
	(title_block
		(title "Bryce Canyon_F.DPB_16315-1-OCP.brd")
		(comment 1 "Bryce Canyon / footprint 2183 of 2223 (IO2), pads 96-109 of 202")
	)
	(layers
		(0 "F.Cu" signal "TOP")
		(4 "In1.Cu" signal "L2GND")
		(6 "In2.Cu" signal "L3")
		(8 "In3.Cu" signal "L4GND")
		(10 "In4.Cu" signal "L5")
		(12 "In5.Cu" signal "L6VCC")
		(14 "In6.Cu" signal "L7VCC")
		(16 "In7.Cu" signal "L8")
		(18 "In8.Cu" signal "L9GND")
		(20 "In9.Cu" signal "L10")
		(22 "In10.Cu" signal "L11GND")
		(2 "B.Cu" signal "BOTTOM")
		(9 "F.Adhes" user "F.Adhesive")
		(11 "B.Adhes" user "B.Adhesive")
		(13 "F.Paste" user "Package Geometry/Pastemask Top")
		(15 "B.Paste" user "Package Geometry/Pastemask Bottom")
		(5 "F.SilkS" user "Ref Des/Silkscreen Top")
		(7 "B.SilkS" user "Ref Des/Silkscreen Bottom")
		(1 "F.Mask" user "Board Geometry/Soldermask Top")
		(3 "B.Mask" user "Board Geometry/Soldermask Bottom")
		(17 "Dwgs.User" user "User.Drawings")
		(19 "Cmts.User" user "User.Comments")
		(21 "Eco1.User" user "User.Eco1")
		(23 "Eco2.User" user "User.Eco2")
		(25 "Edge.Cuts" user "Board Geometry/Outline")
		(27 "Margin" user)
		(31 "F.CrtYd" user "Package Geometry/Place Bound Top")
		(29 "B.CrtYd" user "Package Geometry/Place Bound Bottom")
		(35 "F.Fab" user "Ref Des/Assembly Top")
		(33 "B.Fab" user "Ref Des/Assembly Bottom")
	)
	(footprint ""
		(layer "B.Cu")
		(at 389.349996 -30.550104 180)
		(property "Reference" "IO2"
			(at 0 0 0)
			(layer "B.SilkS")
			(hide yes)
			(effects
				(font
					(size 1.27 1.27)
				)
				(justify mirror)
			)
		)
		(property "Value" "DM-AMP-CONN200-13R-6-GP-01"
			(at 47.5488 -16.5862 180)
			(unlocked yes)
			(layer "B.Fab")
			(hide yes)
			(effects
				(font
					(size 1.016 1.016)
					(thickness 0.1524)
				)
				(justify mirror)
			)
		)
		(property "Device Type" "DMFIT-200P-384346H577-01"
			(at 47.5488 -18.1102 180)
			(unlocked yes)
			(layer "B.Fab")
			(hide yes)
			(effects
				(font
					(size 1.016 1.016)
					(thickness 0.1524)
				)
				(justify mirror)
			)
		)
		(duplicate_pad_numbers_are_jumpers no)
		(pad "F14" thru_hole circle
			(at 30.599888 -9.59993)
			(size 0.664718 0.664718)
			(drill 0.359918)
			(layers "*.Cu" "*.Mask")
			(remove_unused_layers no)
			(net "PCIE_IOM_B_TO_COMP_B_18_DP")
			(clearance 0.264414)
			(padstack
				(mode custom)
				(layer "In1.Cu"
					(shape circle)
					(size 0.664718 0.664718)
					(clearance 0.264414)
				)
				(layer "In2.Cu"
					(shape circle)
					(size 0.664718 0.664718)
					(clearance 0.264414)
				)
				(layer "In3.Cu"
					(shape circle)
					(size 0.664718 0.664718)
					(clearance 0.264414)
				)
				(layer "In4.Cu"
					(shape circle)
					(size 0.664718 0.664718)
					(clearance 0.264414)
				)
				(layer "In5.Cu"
					(shape circle)
					(size 0.664718 0.664718)
					(clearance 0.264414)
				)
				(layer "In6.Cu"
					(shape circle)
					(size 0.762 0.762)
					(clearance 0.1651)
				)
				(layer "In7.Cu"
					(shape circle)
					(size 0.762 0.762)
					(clearance 0.1651)
				)
				(layer "In8.Cu"
					(shape circle)
					(size 0.762 0.762)
					(clearance 0.1651)
				)
				(layer "In9.Cu"
					(shape circle)
					(size 0.762 0.762)
					(clearance 0.1651)
				)
				(layer "In10.Cu"
					(shape circle)
					(size 0.762 0.762)
					(clearance 0.1651)
				)
				(layer "B.Cu"
					(shape circle)
					(size 0.762 0.762)
					(thermal_gap 0.1651)
					(clearance 0.1651)
				)
			)
		)
		(pad "F15" thru_hole circle
			(at 32.399986 -8.599932)
			(size 0.664718 0.664718)
			(drill 0.359918)
			(layers "*.Cu" "*.Mask")
			(remove_unused_layers no)
			(net "PCIE_IOM_B_TO_COMP_B_17_DP")
			(clearance 0.264414)
			(padstack
				(mode custom)
				(layer "In1.Cu"
					(shape circle)
					(size 0.664718 0.664718)
					(clearance 0.264414)
				)
				(layer "In2.Cu"
					(shape circle)
					(size 0.664718 0.664718)
					(clearance 0.264414)
				)
				(layer "In3.Cu"
					(shape circle)
					(size 0.664718 0.664718)
					(clearance 0.264414)
				)
				(layer "In4.Cu"
					(shape circle)
					(size 0.664718 0.664718)
					(clearance 0.264414)
				)
				(layer "In5.Cu"
					(shape circle)
					(size 0.664718 0.664718)
					(clearance 0.264414)
				)
				(layer "In6.Cu"
					(shape circle)
					(size 0.762 0.762)
					(clearance 0.1651)
				)
				(layer "In7.Cu"
					(shape circle)
					(size 0.762 0.762)
					(clearance 0.1651)
				)
				(layer "In8.Cu"
					(shape circle)
					(size 0.762 0.762)
					(clearance 0.1651)
				)
				(layer "In9.Cu"
					(shape circle)
					(size 0.762 0.762)
					(clearance 0.1651)
				)
				(layer "In10.Cu"
					(shape circle)
					(size 0.762 0.762)
					(clearance 0.1651)
				)
				(layer "B.Cu"
					(shape circle)
					(size 0.762 0.762)
					(thermal_gap 0.1651)
					(clearance 0.1651)
				)
			)
		)
		(pad "F16" thru_hole circle
			(at 34.200084 -9.59993)
			(size 0.664718 0.664718)
			(drill 0.359918)
			(layers "*.Cu" "*.Mask")
			(remove_unused_layers no)
			(net "PCIE_IOM_B_TO_COMP_B_16_DP")
			(clearance 0.264414)
			(padstack
				(mode custom)
				(layer "In1.Cu"
					(shape circle)
					(size 0.664718 0.664718)
					(clearance 0.264414)
				)
				(layer "In2.Cu"
					(shape circle)
					(size 0.664718 0.664718)
					(clearance 0.264414)
				)
				(layer "In3.Cu"
					(shape circle)
					(size 0.664718 0.664718)
					(clearance 0.264414)
				)
				(layer "In4.Cu"
					(shape circle)
					(size 0.664718 0.664718)
					(clearance 0.264414)
				)
				(layer "In5.Cu"
					(shape circle)
					(size 0.664718 0.664718)
					(clearance 0.264414)
				)
				(layer "In6.Cu"
					(shape circle)
					(size 0.762 0.762)
					(clearance 0.1651)
				)
				(layer "In7.Cu"
					(shape circle)
					(size 0.762 0.762)
					(clearance 0.1651)
				)
				(layer "In8.Cu"
					(shape circle)
					(size 0.762 0.762)
					(clearance 0.1651)
				)
				(layer "In9.Cu"
					(shape circle)
					(size 0.762 0.762)
					(clearance 0.1651)
				)
				(layer "In10.Cu"
					(shape circle)
					(size 0.762 0.762)
					(clearance 0.1651)
				)
				(layer "B.Cu"
					(shape circle)
					(size 0.762 0.762)
					(thermal_gap 0.1651)
					(clearance 0.1651)
				)
			)
		)
		(pad "G1" thru_hole circle
			(at 0 -10.80008)
			(size 0.664718 0.664718)
			(drill 0.359918)
			(layers "*.Cu" "*.Mask")
			(remove_unused_layers no)
			(net "PCIE_COMP_B_TO_IOM_B_8_DN")
			(clearance 0.264414)
			(padstack
				(mode custom)
				(layer "In1.Cu"
					(shape circle)
					(size 0.664718 0.664718)
					(clearance 0.264414)
				)
				(layer "In2.Cu"
					(shape circle)
					(size 0.664718 0.664718)
					(clearance 0.264414)
				)
				(layer "In3.Cu"
					(shape circle)
					(size 0.664718 0.664718)
					(clearance 0.264414)
				)
				(layer "In4.Cu"
					(shape circle)
					(size 0.664718 0.664718)
					(clearance 0.264414)
				)
				(layer "In5.Cu"
					(shape circle)
					(size 0.664718 0.664718)
					(clearance 0.264414)
				)
				(layer "In6.Cu"
					(shape circle)
					(size 0.762 0.762)
					(clearance 0.1651)
				)
				(layer "In7.Cu"
					(shape circle)
					(size 0.762 0.762)
					(clearance 0.1651)
				)
				(layer "In8.Cu"
					(shape circle)
					(size 0.762 0.762)
					(clearance 0.1651)
				)
				(layer "In9.Cu"
					(shape circle)
					(size 0.762 0.762)
					(clearance 0.1651)
				)
				(layer "In10.Cu"
					(shape circle)
					(size 0.762 0.762)
					(clearance 0.1651)
				)
				(layer "B.Cu"
					(shape circle)
					(size 0.762 0.762)
					(thermal_gap 0.1651)
					(clearance 0.1651)
				)
			)
		)
		(pad "G2" thru_hole circle
			(at 1.800098 -11.800078)
			(size 0.664718 0.664718)
			(drill 0.359918)
			(layers "*.Cu" "*.Mask")
			(remove_unused_layers no)
			(net "PCIE_COMP_B_TO_IOM_B_9_DN")
			(clearance 0.264414)
			(padstack
				(mode custom)
				(layer "In1.Cu"
					(shape circle)
					(size 0.664718 0.664718)
					(clearance 0.264414)
				)
				(layer "In2.Cu"
					(shape circle)
					(size 0.664718 0.664718)
					(clearance 0.264414)
				)
				(layer "In3.Cu"
					(shape circle)
					(size 0.664718 0.664718)
					(clearance 0.264414)
				)
				(layer "In4.Cu"
					(shape circle)
					(size 0.664718 0.664718)
					(clearance 0.264414)
				)
				(layer "In5.Cu"
					(shape circle)
					(size 0.664718 0.664718)
					(clearance 0.264414)
				)
				(layer "In6.Cu"
					(shape circle)
					(size 0.762 0.762)
					(clearance 0.1651)
				)
				(layer "In7.Cu"
					(shape circle)
					(size 0.762 0.762)
					(clearance 0.1651)
				)
				(layer "In8.Cu"
					(shape circle)
					(size 0.762 0.762)
					(clearance 0.1651)
				)
				(layer "In9.Cu"
					(shape circle)
					(size 0.762 0.762)
					(clearance 0.1651)
				)
				(layer "In10.Cu"
					(shape circle)
					(size 0.762 0.762)
					(clearance 0.1651)
				)
				(layer "B.Cu"
					(shape circle)
					(size 0.762 0.762)
					(thermal_gap 0.1651)
					(clearance 0.1651)
				)
			)
		)
		(pad "G3" thru_hole circle
			(at 3.599942 -10.80008)
			(size 0.664718 0.664718)
			(drill 0.359918)
			(layers "*.Cu" "*.Mask")
			(remove_unused_layers no)
			(net "PCIE_COMP_B_TO_IOM_B_10_DN")
			(clearance 0.264414)
			(padstack
				(mode custom)
				(layer "In1.Cu"
					(shape circle)
					(size 0.664718 0.664718)
					(clearance 0.264414)
				)
				(layer "In2.Cu"
					(shape circle)
					(size 0.664718 0.664718)
					(clearance 0.264414)
				)
				(layer "In3.Cu"
					(shape circle)
					(size 0.664718 0.664718)
					(clearance 0.264414)
				)
				(layer "In4.Cu"
					(shape circle)
					(size 0.664718 0.664718)
					(clearance 0.264414)
				)
				(layer "In5.Cu"
					(shape circle)
					(size 0.664718 0.664718)
					(clearance 0.264414)
				)
				(layer "In6.Cu"
					(shape circle)
					(size 0.762 0.762)
					(clearance 0.1651)
				)
				(layer "In7.Cu"
					(shape circle)
					(size 0.762 0.762)
					(clearance 0.1651)
				)
				(layer "In8.Cu"
					(shape circle)
					(size 0.762 0.762)
					(clearance 0.1651)
				)
				(layer "In9.Cu"
					(shape circle)
					(size 0.762 0.762)
					(clearance 0.1651)
				)
				(layer "In10.Cu"
					(shape circle)
					(size 0.762 0.762)
					(clearance 0.1651)
				)
				(layer "B.Cu"
					(shape circle)
					(size 0.762 0.762)
					(thermal_gap 0.1651)
					(clearance 0.1651)
				)
			)
		)
		(pad "G4" thru_hole circle
			(at 5.40004 -11.800078)
			(size 0.664718 0.664718)
			(drill 0.359918)
			(layers "*.Cu" "*.Mask")
			(remove_unused_layers no)
			(net "PCIE_COMP_B_TO_IOM_B_11_DN")
			(clearance 0.264414)
			(padstack
				(mode custom)
				(layer "In1.Cu"
					(shape circle)
					(size 0.664718 0.664718)
					(clearance 0.264414)
				)
				(layer "In2.Cu"
					(shape circle)
					(size 0.664718 0.664718)
					(clearance 0.264414)
				)
				(layer "In3.Cu"
					(shape circle)
					(size 0.664718 0.664718)
					(clearance 0.264414)
				)
				(layer "In4.Cu"
					(shape circle)
					(size 0.664718 0.664718)
					(clearance 0.264414)
				)
				(layer "In5.Cu"
					(shape circle)
					(size 0.664718 0.664718)
					(clearance 0.264414)
				)
				(layer "In6.Cu"
					(shape circle)
					(size 0.762 0.762)
					(clearance 0.1651)
				)
				(layer "In7.Cu"
					(shape circle)
					(size 0.762 0.762)
					(clearance 0.1651)
				)
				(layer "In8.Cu"
					(shape circle)
					(size 0.762 0.762)
					(clearance 0.1651)
				)
				(layer "In9.Cu"
					(shape circle)
					(size 0.762 0.762)
					(clearance 0.1651)
				)
				(layer "In10.Cu"
					(shape circle)
					(size 0.762 0.762)
					(clearance 0.1651)
				)
				(layer "B.Cu"
					(shape circle)
					(size 0.762 0.762)
					(thermal_gap 0.1651)
					(clearance 0.1651)
				)
			)
		)
		(pad "G5" thru_hole circle
			(at 7.199884 -10.80008)
			(size 0.664718 0.664718)
			(drill 0.359918)
			(layers "*.Cu" "*.Mask")
			(remove_unused_layers no)
			(net "PCIE_COMP_B_TO_IOM_B_12_DN")
			(clearance 0.264414)
			(padstack
				(mode custom)
				(layer "In1.Cu"
					(shape circle)
					(size 0.664718 0.664718)
					(clearance 0.264414)
				)
				(layer "In2.Cu"
					(shape circle)
					(size 0.664718 0.664718)
					(clearance 0.264414)
				)
				(layer "In3.Cu"
					(shape circle)
					(size 0.664718 0.664718)
					(clearance 0.264414)
				)
				(layer "In4.Cu"
					(shape circle)
					(size 0.664718 0.664718)
					(clearance 0.264414)
				)
				(layer "In5.Cu"
					(shape circle)
					(size 0.664718 0.664718)
					(clearance 0.264414)
				)
				(layer "In6.Cu"
					(shape circle)
					(size 0.762 0.762)
					(clearance 0.1651)
				)
				(layer "In7.Cu"
					(shape circle)
					(size 0.762 0.762)
					(clearance 0.1651)
				)
				(layer "In8.Cu"
					(shape circle)
					(size 0.762 0.762)
					(clearance 0.1651)
				)
				(layer "In9.Cu"
					(shape circle)
					(size 0.762 0.762)
					(clearance 0.1651)
				)
				(layer "In10.Cu"
					(shape circle)
					(size 0.762 0.762)
					(clearance 0.1651)
				)
				(layer "B.Cu"
					(shape circle)
					(size 0.762 0.762)
					(thermal_gap 0.1651)
					(clearance 0.1651)
				)
			)
		)
		(pad "G6" thru_hole circle
			(at 8.999982 -11.800078)
			(size 0.664718 0.664718)
			(drill 0.359918)
			(layers "*.Cu" "*.Mask")
			(remove_unused_layers no)
			(net "PCIE_COMP_B_TO_IOM_B_13_DN")
			(clearance 0.264414)
			(padstack
				(mode custom)
				(layer "In1.Cu"
					(shape circle)
					(size 0.664718 0.664718)
					(clearance 0.264414)
				)
				(layer "In2.Cu"
					(shape circle)
					(size 0.664718 0.664718)
					(clearance 0.264414)
				)
				(layer "In3.Cu"
					(shape circle)
					(size 0.664718 0.664718)
					(clearance 0.264414)
				)
				(layer "In4.Cu"
					(shape circle)
					(size 0.664718 0.664718)
					(clearance 0.264414)
				)
				(layer "In5.Cu"
					(shape circle)
					(size 0.664718 0.664718)
					(clearance 0.264414)
				)
				(layer "In6.Cu"
					(shape circle)
					(size 0.762 0.762)
					(clearance 0.1651)
				)
				(layer "In7.Cu"
					(shape circle)
					(size 0.762 0.762)
					(clearance 0.1651)
				)
				(layer "In8.Cu"
					(shape circle)
					(size 0.762 0.762)
					(clearance 0.1651)
				)
				(layer "In9.Cu"
					(shape circle)
					(size 0.762 0.762)
					(clearance 0.1651)
				)
				(layer "In10.Cu"
					(shape circle)
					(size 0.762 0.762)
					(clearance 0.1651)
				)
				(layer "B.Cu"
					(shape circle)
					(size 0.762 0.762)
					(thermal_gap 0.1651)
					(clearance 0.1651)
				)
			)
		)
		(pad "G7" thru_hole circle
			(at 10.80008 -10.80008)
			(size 0.664718 0.664718)
			(drill 0.359918)
			(layers "*.Cu" "*.Mask")
			(remove_unused_layers no)
			(net "PCIE_COMP_B_TO_IOM_B_14_DN")
			(clearance 0.264414)
			(padstack
				(mode custom)
				(layer "In1.Cu"
					(shape circle)
					(size 0.664718 0.664718)
					(clearance 0.264414)
				)
				(layer "In2.Cu"
					(shape circle)
					(size 0.664718 0.664718)
					(clearance 0.264414)
				)
				(layer "In3.Cu"
					(shape circle)
					(size 0.664718 0.664718)
					(clearance 0.264414)
				)
				(layer "In4.Cu"
					(shape circle)
					(size 0.664718 0.664718)
					(clearance 0.264414)
				)
				(layer "In5.Cu"
					(shape circle)
					(size 0.664718 0.664718)
					(clearance 0.264414)
				)
				(layer "In6.Cu"
					(shape circle)
					(size 0.762 0.762)
					(clearance 0.1651)
				)
				(layer "In7.Cu"
					(shape circle)
					(size 0.762 0.762)
					(clearance 0.1651)
				)
				(layer "In8.Cu"
					(shape circle)
					(size 0.762 0.762)
					(clearance 0.1651)
				)
				(layer "In9.Cu"
					(shape circle)
					(size 0.762 0.762)
					(clearance 0.1651)
				)
				(layer "In10.Cu"
					(shape circle)
					(size 0.762 0.762)
					(clearance 0.1651)
				)
				(layer "B.Cu"
					(shape circle)
					(size 0.762 0.762)
					(thermal_gap 0.1651)
					(clearance 0.1651)
				)
			)
		)
		(pad "G8" thru_hole circle
			(at 12.599924 -11.800078)
			(size 0.664718 0.664718)
			(drill 0.359918)
			(layers "*.Cu" "*.Mask")
			(remove_unused_layers no)
			(net "PCIE_COMP_B_TO_IOM_B_15_DN")
			(clearance 0.264414)
			(padstack
				(mode custom)
				(layer "In1.Cu"
					(shape circle)
					(size 0.664718 0.664718)
					(clearance 0.264414)
				)
				(layer "In2.Cu"
					(shape circle)
					(size 0.664718 0.664718)
					(clearance 0.264414)
				)
				(layer "In3.Cu"
					(shape circle)
					(size 0.664718 0.664718)
					(clearance 0.264414)
				)
				(layer "In4.Cu"
					(shape circle)
					(size 0.664718 0.664718)
					(clearance 0.264414)
				)
				(layer "In5.Cu"
					(shape circle)
					(size 0.664718 0.664718)
					(clearance 0.264414)
				)
				(layer "In6.Cu"
					(shape circle)
					(size 0.762 0.762)
					(clearance 0.1651)
				)
				(layer "In7.Cu"
					(shape circle)
					(size 0.762 0.762)
					(clearance 0.1651)
				)
				(layer "In8.Cu"
					(shape circle)
					(size 0.762 0.762)
					(clearance 0.1651)
				)
				(layer "In9.Cu"
					(shape circle)
					(size 0.762 0.762)
					(clearance 0.1651)
				)
				(layer "In10.Cu"
					(shape circle)
					(size 0.762 0.762)
					(clearance 0.1651)
				)
				(layer "B.Cu"
					(shape circle)
					(size 0.762 0.762)
					(thermal_gap 0.1651)
					(clearance 0.1651)
				)
			)
		)
		(pad "G9" thru_hole circle
			(at 21.599906 -10.80008)
			(size 0.664718 0.664718)
			(drill 0.359918)
			(layers "*.Cu" "*.Mask")
			(remove_unused_layers no)
			(net "PCIE_COMP_B_TO_IOM_B_23_DN")
			(clearance 0.264414)
			(padstack
				(mode custom)
				(layer "In1.Cu"
					(shape circle)
					(size 0.664718 0.664718)
					(clearance 0.264414)
				)
				(layer "In2.Cu"
					(shape circle)
					(size 0.664718 0.664718)
					(clearance 0.264414)
				)
				(layer "In3.Cu"
					(shape circle)
					(size 0.664718 0.664718)
					(clearance 0.264414)
				)
				(layer "In4.Cu"
					(shape circle)
					(size 0.664718 0.664718)
					(clearance 0.264414)
				)
				(layer "In5.Cu"
					(shape circle)
					(size 0.664718 0.664718)
					(clearance 0.264414)
				)
				(layer "In6.Cu"
					(shape circle)
					(size 0.762 0.762)
					(clearance 0.1651)
				)
				(layer "In7.Cu"
					(shape circle)
					(size 0.762 0.762)
					(clearance 0.1651)
				)
				(layer "In8.Cu"
					(shape circle)
					(size 0.762 0.762)
					(clearance 0.1651)
				)
				(layer "In9.Cu"
					(shape circle)
					(size 0.762 0.762)
					(clearance 0.1651)
				)
				(layer "In10.Cu"
					(shape circle)
					(size 0.762 0.762)
					(clearance 0.1651)
				)
				(layer "B.Cu"
					(shape circle)
					(size 0.762 0.762)
					(thermal_gap 0.1651)
					(clearance 0.1651)
				)
			)
		)
		(pad "G10" thru_hole circle
			(at 23.400004 -11.800078)
			(size 0.664718 0.664718)
			(drill 0.359918)
			(layers "*.Cu" "*.Mask")
			(remove_unused_layers no)
			(net "PCIE_COMP_B_TO_IOM_B_22_DN")
			(clearance 0.264414)
			(padstack
				(mode custom)
				(layer "In1.Cu"
					(shape circle)
					(size 0.664718 0.664718)
					(clearance 0.264414)
				)
				(layer "In2.Cu"
					(shape circle)
					(size 0.664718 0.664718)
					(clearance 0.264414)
				)
				(layer "In3.Cu"
					(shape circle)
					(size 0.664718 0.664718)
					(clearance 0.264414)
				)
				(layer "In4.Cu"
					(shape circle)
					(size 0.664718 0.664718)
					(clearance 0.264414)
				)
				(layer "In5.Cu"
					(shape circle)
					(size 0.664718 0.664718)
					(clearance 0.264414)
				)
				(layer "In6.Cu"
					(shape circle)
					(size 0.762 0.762)
					(clearance 0.1651)
				)
				(layer "In7.Cu"
					(shape circle)
					(size 0.762 0.762)
					(clearance 0.1651)
				)
				(layer "In8.Cu"
					(shape circle)
					(size 0.762 0.762)
					(clearance 0.1651)
				)
				(layer "In9.Cu"
					(shape circle)
					(size 0.762 0.762)
					(clearance 0.1651)
				)
				(layer "In10.Cu"
					(shape circle)
					(size 0.762 0.762)
					(clearance 0.1651)
				)
				(layer "B.Cu"
					(shape circle)
					(size 0.762 0.762)
					(thermal_gap 0.1651)
					(clearance 0.1651)
				)
			)
		)
		(pad "G11" thru_hole circle
			(at 25.200102 -10.80008)
			(size 0.664718 0.664718)
			(drill 0.359918)
			(layers "*.Cu" "*.Mask")
			(remove_unused_layers no)
			(net "PCIE_COMP_B_TO_IOM_B_21_DN")
			(clearance 0.264414)
			(padstack
				(mode custom)
				(layer "In1.Cu"
					(shape circle)
					(size 0.664718 0.664718)
					(clearance 0.264414)
				)
				(layer "In2.Cu"
					(shape circle)
					(size 0.664718 0.664718)
					(clearance 0.264414)
				)
				(layer "In3.Cu"
					(shape circle)
					(size 0.664718 0.664718)
					(clearance 0.264414)
				)
				(layer "In4.Cu"
					(shape circle)
					(size 0.664718 0.664718)
					(clearance 0.264414)
				)
				(layer "In5.Cu"
					(shape circle)
					(size 0.664718 0.664718)
					(clearance 0.264414)
				)
				(layer "In6.Cu"
					(shape circle)
					(size 0.762 0.762)
					(clearance 0.1651)
				)
				(layer "In7.Cu"
					(shape circle)
					(size 0.762 0.762)
					(clearance 0.1651)
				)
				(layer "In8.Cu"
					(shape circle)
					(size 0.762 0.762)
					(clearance 0.1651)
				)
				(layer "In9.Cu"
					(shape circle)
					(size 0.762 0.762)
					(clearance 0.1651)
				)
				(layer "In10.Cu"
					(shape circle)
					(size 0.762 0.762)
					(clearance 0.1651)
				)
				(layer "B.Cu"
					(shape circle)
					(size 0.762 0.762)
					(thermal_gap 0.1651)
					(clearance 0.1651)
				)
			)
		)
	)
)
